(kicad_pcb
	(version 20260206)
	(generator "pcbnew")
	(generator_version "10.0")
	(general
		(thickness 1.6)
		(legacy_teardrops no)
	)
	(paper "A4")
	(title_block
		(title "fcb — Lightning_FCB_BRD.brd")
		(comment 1 "Lightning (Wiwynn / Facebook NVMe JBOF) / footprints 412-417 of 495")
	)
	(layers
		(0 "F.Cu" signal "TOP")
		(4 "In1.Cu" signal "L2GND")
		(6 "In2.Cu" signal "L3VCC")
		(2 "B.Cu" signal "BOTTOM")
		(9 "F.Adhes" user "F.Adhesive")
		(11 "B.Adhes" user "B.Adhesive")
		(13 "F.Paste" user "Package Geometry/Pastemask Top")
		(15 "B.Paste" user "Package Geometry/Pastemask Bottom")
		(5 "F.SilkS" user "Ref Des/Silkscreen Top")
		(7 "B.SilkS" user "Ref Des/Silkscreen Bottom")
		(1 "F.Mask" user "Board Geometry/Soldermask Top")
		(3 "B.Mask" user "Board Geometry/Soldermask Bottom")
		(17 "Dwgs.User" user "User.Drawings")
		(19 "Cmts.User" user "User.Comments")
		(21 "Eco1.User" user "User.Eco1")
		(23 "Eco2.User" user "User.Eco2")
		(25 "Edge.Cuts" user "Board Geometry/Outline")
		(27 "Margin" user)
		(31 "F.CrtYd" user "Package Geometry/Place Bound Top")
		(29 "B.CrtYd" user "Package Geometry/Place Bound Bottom")
		(35 "F.Fab" user "Ref Des/Assembly Top")
		(33 "B.Fab" user "Ref Des/Assembly Bottom")
	)
	(footprint ""
		(layer "F.Cu")
		(at 47.0154 -418.592 90)
		(property "Reference" "C25"
			(at 0 0 90)
			(layer "F.SilkS")
			(hide yes)
			(effects
				(font
					(size 1.27 1.27)
				)
			)
		)
		(property "Value" "SCD1U50V3KX-GP"
			(at 0 -2.8194 90)
			(unlocked yes)
			(layer "F.Fab")
			(hide yes)
			(effects
				(font
					(size 1.016 1.016)
					(thickness 0.1524)
				)
			)
		)
		(property "Device Type" "C603H36"
			(at 0 -4.3434 90)
			(unlocked yes)
			(layer "F.Fab")
			(hide yes)
			(effects
				(font
					(size 1.016 1.016)
					(thickness 0.1524)
				)
			)
		)
		(duplicate_pad_numbers_are_jumpers no)
		(fp_line
			(start 0.508 0)
			(end -0.508 0)
			(stroke
				(width 0.2032)
				(type default)
			)
			(layer "F.SilkS")
		)
		(fp_rect
			(start -0.5842 1.3335)
			(end 0.5842 -1.3335)
			(stroke
				(width 0)
				(type default)
			)
			(fill no)
			(layer "F.CrtYd")
		)
		(fp_rect
			(start -0.5842 1.3335)
			(end 0.5842 -1.3335)
			(stroke
				(width 0)
				(type default)
			)
			(fill no)
			(layer "F.Fab")
		)
		(pad "1" smd custom
			(at 0 -0.762 90)
			(size 0.2159 0.2159)
			(layers "F.Cu" "F.Mask" "F.Paste")
			(net "P12V_AUX")
			(options
				(clearance outline)
				(anchor circle)
			)
			(primitives
				(gr_poly
					(pts
						(arc
							(start -0.3302 -0.4318)
							(mid -0.402042 -0.402042)
							(end -0.4318 -0.3302)
						)
						(arc
							(start -0.4318 0.3302)
							(mid -0.402042 0.402042)
							(end -0.3302 0.4318)
						)
						(arc
							(start 0.3302 0.4318)
							(mid 0.402042 0.402042)
							(end 0.4318 0.3302)
						)
						(arc
							(start 0.4318 -0.3302)
							(mid 0.402042 -0.402042)
							(end 0.3302 -0.4318)
						)
					)
					(width 0)
					(fill yes)
				)
			)
		)
		(pad "2" smd custom
			(at 0 0.762 90)
			(size 0.2159 0.2159)
			(layers "F.Cu" "F.Mask" "F.Paste")
			(net "GND")
			(options
				(clearance outline)
				(anchor circle)
			)
			(primitives
				(gr_poly
					(pts
						(arc
							(start -0.3302 -0.4318)
							(mid -0.402042 -0.402042)
							(end -0.4318 -0.3302)
						)
						(arc
							(start -0.4318 0.3302)
							(mid -0.402042 0.402042)
							(end -0.3302 0.4318)
						)
						(arc
							(start 0.3302 0.4318)
							(mid 0.402042 0.402042)
							(end 0.4318 0.3302)
						)
						(arc
							(start 0.4318 -0.3302)
							(mid 0.402042 -0.402042)
							(end 0.3302 -0.4318)
						)
					)
					(width 0)
					(fill yes)
				)
			)
		)
	)
	(footprint ""
		(layer "F.Cu")
		(at 14.8844 -44.5262 90)
		(property "Reference" "R171"
			(at 0 0 90)
			(layer "F.SilkS")
			(hide yes)
			(effects
				(font
					(size 1.27 1.27)
				)
			)
		)
		(property "Value" "0R2J-2-GP"
			(at 0.064008 -3.993896 90)
			(unlocked yes)
			(layer "F.Fab")
			(hide yes)
			(effects
				(font
					(size 1.016 1.016)
					(thickness 0.1524)
				)
			)
		)
		(property "Device Type" "R402H16"
			(at 0.064008 -5.517896 90)
			(unlocked yes)
			(layer "F.Fab")
			(hide yes)
			(effects
				(font
					(size 1.016 1.016)
					(thickness 0.1524)
				)
			)
		)
		(duplicate_pad_numbers_are_jumpers no)
		(fp_line
			(start 0.508 -0.9398)
			(end -0.508 -0.9398)
			(stroke
				(width 0.1524)
				(type default)
			)
			(layer "F.SilkS")
		)
		(fp_line
			(start -0.508 -0.9398)
			(end -0.508 0.9398)
			(stroke
				(width 0.1524)
				(type default)
			)
			(layer "F.SilkS")
		)
		(fp_rect
			(start -0.508 0.9398)
			(end 0.508 -0.9398)
			(stroke
				(width 0)
				(type default)
			)
			(fill no)
			(layer "F.CrtYd")
		)
		(fp_rect
			(start -0.508 0.9398)
			(end 0.508 -0.9398)
			(stroke
				(width 0)
				(type default)
			)
			(fill no)
			(layer "F.Fab")
		)
		(pad "1" smd custom
			(at 0 -0.4445 90)
			(size 0.1397 0.1397)
			(layers "F.Cu" "F.Mask" "F.Paste")
			(net "SELF_1A_HB")
			(options
				(clearance outline)
				(anchor circle)
			)
			(primitives
				(gr_poly
					(pts
						(arc
							(start -0.1778 -0.2794)
							(mid -0.249642 -0.249642)
							(end -0.2794 -0.1778)
						)
						(arc
							(start -0.2794 0.1778)
							(mid -0.249642 0.249642)
							(end -0.1778 0.2794)
						)
						(arc
							(start 0.1778 0.2794)
							(mid 0.249642 0.249642)
							(end 0.2794 0.1778)
						)
						(arc
							(start 0.2794 -0.1778)
							(mid 0.249642 -0.249642)
							(end 0.1778 -0.2794)
						)
					)
					(width 0)
					(fill yes)
				)
			)
		)
		(pad "2" smd custom
			(at 0 0.4445 90)
			(size 0.1397 0.1397)
			(layers "F.Cu" "F.Mask" "F.Paste")
			(net "SEB_PEER_2A_HB")
			(options
				(clearance outline)
				(anchor circle)
			)
			(primitives
				(gr_poly
					(pts
						(arc
							(start -0.1778 -0.2794)
							(mid -0.249642 -0.249642)
							(end -0.2794 -0.1778)
						)
						(arc
							(start -0.2794 0.1778)
							(mid -0.249642 0.249642)
							(end -0.1778 0.2794)
						)
						(arc
							(start 0.1778 0.2794)
							(mid 0.249642 0.249642)
							(end 0.2794 0.1778)
						)
						(arc
							(start 0.2794 -0.1778)
							(mid 0.249642 -0.249642)
							(end 0.1778 -0.2794)
						)
					)
					(width 0)
					(fill yes)
				)
			)
		)
	)
	(footprint ""
		(layer "F.Cu")
		(at 31.571692 -481.559362 180)
		(property "Reference" "TC18"
			(at 0 0 180)
			(layer "F.SilkS")
			(hide yes)
			(effects
				(font
					(size 1.27 1.27)
				)
			)
		)
		(property "Value" "ST15U25VDM-1-GP"
			(at 0 -9.6012 180)
			(unlocked yes)
			(layer "F.Fab")
			(hide yes)
			(effects
				(font
					(size 1.016 1.016)
					(thickness 0.1524)
				)
			)
		)
		(property "Device Type" "CT7343H79"
			(at 0 -11.1252 180)
			(unlocked yes)
			(layer "F.Fab")
			(hide yes)
			(effects
				(font
					(size 1.016 1.016)
					(thickness 0.1524)
				)
			)
		)
		(duplicate_pad_numbers_are_jumpers no)
		(fp_line
			(start 2.286 4.8768)
			(end -2.286 4.8768)
			(stroke
				(width 0.1524)
				(type default)
			)
			(layer "F.SilkS")
		)
		(fp_line
			(start 2.286 2.032)
			(end 2.286 4.8768)
			(stroke
				(width 0.1524)
				(type default)
			)
			(layer "F.SilkS")
		)
		(fp_line
			(start 2.286 -2.032)
			(end 2.286 -4.8768)
			(stroke
				(width 0.1524)
				(type default)
			)
			(layer "F.SilkS")
		)
		(fp_line
			(start 2.286 -4.8768)
			(end -2.286 -4.8768)
			(stroke
				(width 0.1524)
				(type default)
			)
			(layer "F.SilkS")
		)
		(fp_line
			(start 2.1082 -4.699)
			(end -2.1082 -4.699)
			(stroke
				(width 0.508)
				(type default)
			)
			(layer "F.SilkS")
		)
		(fp_line
			(start -2.286 4.8768)
			(end -2.286 2.032)
			(stroke
				(width 0.1524)
				(type default)
			)
			(layer "F.SilkS")
		)
		(fp_line
			(start -2.286 -4.8768)
			(end -2.286 -2.032)
			(stroke
				(width 0.1524)
				(type default)
			)
			(layer "F.SilkS")
		)
		(fp_rect
			(start -2.1463 3.6449)
			(end 2.1463 -3.6449)
			(stroke
				(width 0)
				(type default)
			)
			(fill no)
			(layer "F.CrtYd")
		)
		(fp_poly
			(pts
				(xy -2.54 4.953) (xy -2.54 4.2926) (xy -3.81 4.2926) (xy -3.81 -4.2926) (xy -2.54 -4.2926) (xy -2.54 -4.953)
				(xy 2.54 -4.953) (xy 2.54 -4.2926) (xy 3.81 -4.2926) (xy 3.81 -1.6256) (xy 2.1463 -1.6256) (xy 2.1463 -3.6449)
				(xy -2.1463 -3.6449) (xy -2.1463 3.6449) (xy 2.1463 3.6449) (xy 2.1463 -1.6129) (xy 3.81 -1.6129)
				(xy 3.81 4.2926) (xy 2.54 4.2926) (xy 2.54 4.953)
			)
			(stroke
				(width 0)
				(type default)
			)
			(fill no)
			(layer "F.CrtYd")
		)
		(fp_rect
			(start 2.54 4.2926)
			(end 3.81 -4.2926)
			(stroke
				(width 0)
				(type default)
			)
			(fill no)
			(layer "F.Fab")
		)
		(fp_rect
			(start -2.54 4.953)
			(end 2.54 -4.953)
			(stroke
				(width 0)
				(type default)
			)
			(fill no)
			(layer "F.Fab")
		)
		(fp_rect
			(start -3.81 4.2926)
			(end -2.54 -4.2926)
			(stroke
				(width 0)
				(type default)
			)
			(fill no)
			(layer "F.Fab")
		)
		(pad "1" smd rect
			(at 0 -3.1496 180)
			(size 2.413 2.286)
			(layers "F.Cu" "F.Mask" "F.Paste")
			(net "P12V")
		)
		(pad "2" smd rect
			(at 0 3.1496 180)
			(size 2.413 2.286)
			(layers "F.Cu" "F.Mask" "F.Paste")
			(net "GND")
		)
		(zone
			(layer "F.Cu")
			(hatch none 0.5)
			(connect_pads
				(clearance 0)
			)
			(min_thickness 0.25)
			(keepout
				(tracks allowed)
				(vias not_allowed)
				(pads allowed)
				(copperpour not_allowed)
				(footprints allowed)
			)
			(placement
				(enabled no)
				(sheetname "")
			)
			(fill
				(thermal_gap 0.5)
				(thermal_bridge_width 0.5)
				(island_removal_mode 0)
			)
			(polygon
				(pts
					(xy 30.060392 -479.870262) (xy 30.060392 -476.961962) (xy 33.082992 -476.961962) (xy 33.082992 -479.857562)
					(xy 33.082992 -480.187762) (xy 30.060392 -480.187762)
				)
			)
		)
		(zone
			(layer "F.Cu")
			(hatch none 0.5)
			(connect_pads
				(clearance 0)
			)
			(min_thickness 0.25)
			(keepout
				(tracks allowed)
				(vias not_allowed)
				(pads allowed)
				(copperpour not_allowed)
				(footprints allowed)
			)
			(placement
				(enabled no)
				(sheetname "")
			)
			(fill
				(thermal_gap 0.5)
				(thermal_bridge_width 0.5)
				(island_removal_mode 0)
			)
			(polygon
				(pts
					(xy 33.082992 -486.156762) (xy 30.060392 -486.156762) (xy 30.060392 -483.261162) (xy 30.060392 -482.930962)
					(xy 33.082992 -482.930962) (xy 33.082992 -483.261162)
				)
			)
		)
	)
	(footprint ""
		(layer "F.Cu")
		(at 40.26789 -154.147266 180)
		(property "Reference" "L1"
			(at 0 0 180)
			(layer "F.SilkS")
			(hide yes)
			(effects
				(font
					(size 1.27 1.27)
				)
			)
		)
		(property "Value" "FCM1608CF-121T03-GP"
			(at -0.0254 -2.8956 180)
			(unlocked yes)
			(layer "F.Fab")
			(hide yes)
			(effects
				(font
					(size 1.016 1.016)
					(thickness 0.1524)
				)
			)
		)
		(property "Device Type" "L1608-UH38"
			(at -0.0254 -4.4196 180)
			(unlocked yes)
			(layer "F.Fab")
			(hide yes)
			(effects
				(font
					(size 1.016 1.016)
					(thickness 0.1524)
				)
			)
		)
		(duplicate_pad_numbers_are_jumpers no)
		(fp_line
			(start 0.254 0)
			(end -0.254 0)
			(stroke
				(width 0.2032)
				(type default)
			)
			(layer "F.SilkS")
		)
		(fp_rect
			(start -0.5842 1.3335)
			(end 0.5842 -1.3335)
			(stroke
				(width 0)
				(type default)
			)
			(fill no)
			(layer "F.CrtYd")
		)
		(fp_rect
			(start -0.5842 1.3335)
			(end 0.5842 -1.3335)
			(stroke
				(width 0)
				(type default)
			)
			(fill no)
			(layer "F.Fab")
		)
		(pad "1" smd custom
			(at 0 -0.762 180)
			(size 0.2159 0.2159)
			(layers "F.Cu" "F.Mask" "F.Paste")
			(net "P3V3")
			(options
				(clearance outline)
				(anchor circle)
			)
			(primitives
				(gr_poly
					(pts
						(arc
							(start -0.3302 -0.4318)
							(mid -0.402042 -0.402042)
							(end -0.4318 -0.3302)
						)
						(arc
							(start -0.4318 0.3302)
							(mid -0.402042 0.402042)
							(end -0.3302 0.4318)
						)
						(arc
							(start 0.3302 0.4318)
							(mid 0.402042 0.402042)
							(end 0.4318 0.3302)
						)
						(arc
							(start 0.4318 -0.3302)
							(mid 0.402042 -0.402042)
							(end 0.3302 -0.4318)
						)
					)
					(width 0)
					(fill yes)
				)
			)
		)
		(pad "2" smd custom
			(at 0 0.762 180)
			(size 0.2159 0.2159)
			(layers "F.Cu" "F.Mask" "F.Paste")
			(net "NCT7904_3VDD")
			(options
				(clearance outline)
				(anchor circle)
			)
			(primitives
				(gr_poly
					(pts
						(arc
							(start -0.3302 -0.4318)
							(mid -0.402042 -0.402042)
							(end -0.4318 -0.3302)
						)
						(arc
							(start -0.4318 0.3302)
							(mid -0.402042 0.402042)
							(end -0.3302 0.4318)
						)
						(arc
							(start 0.3302 0.4318)
							(mid 0.402042 0.402042)
							(end 0.4318 0.3302)
						)
						(arc
							(start 0.4318 -0.3302)
							(mid 0.402042 -0.402042)
							(end 0.3302 -0.4318)
						)
					)
					(width 0)
					(fill yes)
				)
			)
		)
	)
	(footprint ""
		(layer "F.Cu")
		(at 42.05859 -162.643566 180)
		(property "Reference" "OSC1"
			(at 0 0 180)
			(layer "F.SilkS")
			(hide yes)
			(effects
				(font
					(size 1.27 1.27)
				)
			)
		)
		(property "Value" "OSC-33MHZ-7-GP"
			(at 0 -10.1092 180)
			(unlocked yes)
			(layer "F.Fab")
			(hide yes)
			(effects
				(font
					(size 1.016 1.016)
					(thickness 0.1524)
				)
			)
		)
		(property "Device Type" "SMD-OSC8H52"
			(at 0 -11.6332 180)
			(unlocked yes)
			(layer "F.Fab")
			(hide yes)
			(effects
				(font
					(size 1.016 1.016)
					(thickness 0.1524)
				)
			)
		)
		(duplicate_pad_numbers_are_jumpers no)
		(fp_line
			(start 2.7559 2.4638)
			(end -2.7559 2.4638)
			(stroke
				(width 0.1524)
				(type default)
			)
			(layer "F.SilkS")
		)
		(fp_line
			(start 2.7559 -2.4638)
			(end 2.7559 2.4638)
			(stroke
				(width 0.1524)
				(type default)
			)
			(layer "F.SilkS")
		)
		(fp_line
			(start -1.242822 2.55143)
			(end -2.852166 2.55143)
			(stroke
				(width 0.3302)
				(type default)
			)
			(layer "F.SilkS")
		)
		(fp_line
			(start -2.7559 2.4638)
			(end -2.7559 -2.4638)
			(stroke
				(width 0.1524)
				(type default)
			)
			(layer "F.SilkS")
		)
		(fp_line
			(start -2.7559 -2.4638)
			(end 2.7559 -2.4638)
			(stroke
				(width 0.1524)
				(type default)
			)
			(layer "F.SilkS")
		)
		(fp_line
			(start -2.852166 2.55143)
			(end -2.852166 1.131316)
			(stroke
				(width 0.3302)
				(type default)
			)
			(layer "F.SilkS")
		)
		(fp_poly
			(pts
				(xy -1.778 3.0734) (xy -1.2446 2.54) (xy -0.762 3.0734)
			)
			(stroke
				(width 0)
				(type default)
			)
			(fill yes)
			(layer "F.SilkS")
		)
		(fp_poly
			(pts
				(xy -3.0099 2.7178) (xy -3.0099 -2.7178) (xy 3.0099 -2.7178) (xy 3.0099 2.7178)
			)
			(stroke
				(width 0)
				(type default)
			)
			(fill no)
			(layer "F.CrtYd")
		)
		(fp_poly
			(pts
				(xy -3.0099 -2.7178) (xy 3.0099 -2.7178) (xy 3.0099 2.7178) (xy -3.0099 2.7178)
			)
			(stroke
				(width 0)
				(type default)
			)
			(fill no)
			(layer "F.Fab")
		)
		(pad "1" smd rect
			(at -1.46939 1.39954 180)
			(size 1.8034 1.6002)
			(layers "F.Cu" "F.Mask" "F.Paste")
			(net "OSC_TRI_S")
		)
		(pad "2" smd rect
			(at 1.46939 1.39954 180)
			(size 1.8034 1.6002)
			(layers "F.Cu" "F.Mask" "F.Paste")
			(net "GND")
		)
		(pad "3" smd rect
			(at 1.46939 -1.39954 180)
			(size 1.8034 1.6002)
			(layers "F.Cu" "F.Mask" "F.Paste")
			(net "NCT7904_CLK")
		)
		(pad "4" smd rect
			(at -1.46939 -1.39954 180)
			(size 1.8034 1.6002)
			(layers "F.Cu" "F.Mask" "F.Paste")
			(net "P3V3")
		)
		(zone
			(layer "F.Cu")
			(hatch none 0.5)
			(connect_pads
				(clearance 0)
			)
			(min_thickness 0.25)
			(keepout
				(tracks not_allowed)
				(vias allowed)
				(pads allowed)
				(copperpour not_allowed)
				(footprints allowed)
			)
			(placement
				(enabled no)
				(sheetname "")
			)
			(fill
				(thermal_gap 0.5)
				(thermal_bridge_width 0.5)
				(island_removal_mode 0)
			)
			(polygon
				(pts
					(xy 42.302938 -162.367468) (xy 42.302938 -162.919664) (xy 41.814242 -162.919664) (xy 41.814242 -162.367468)
				)
			)
		)
		(zone
			(layer "F.Cu")
			(hatch none 0.5)
			(connect_pads
				(clearance 0)
			)
			(min_thickness 0.25)
			(keepout
				(tracks allowed)
				(vias not_allowed)
				(pads allowed)
				(copperpour not_allowed)
				(footprints allowed)
			)
			(placement
				(enabled no)
				(sheetname "")
			)
			(fill
				(thermal_gap 0.5)
				(thermal_bridge_width 0.5)
				(island_removal_mode 0)
			)
			(polygon
				(pts
					(xy 42.62628 -164.843206) (xy 42.62628 -163.243006) (xy 44.42968 -163.243006) (xy 44.42968 -162.044126)
					(xy 42.62628 -162.044126) (xy 42.62628 -160.443926) (xy 41.4909 -160.443926) (xy 41.4909 -162.044126)
					(xy 39.6875 -162.044126) (xy 39.6875 -163.243006) (xy 41.4909 -163.243006) (xy 41.4909 -164.843206)
				)
			)
		)
	)
	(footprint ""
		(layer "F.Cu")
		(at 46.863 -416.814 90)
		(property "Reference" "PC8"
			(at 0 0 90)
			(layer "F.SilkS")
			(hide yes)
			(effects
				(font
					(size 1.27 1.27)
				)
			)
		)
		(property "Value" "SC1U25V5KX-1GP"
			(at -0.0762 -6.1214 90)
			(unlocked yes)
			(layer "F.Fab")
			(hide yes)
			(effects
				(font
					(size 1.016 1.016)
					(thickness 0.1524)
				)
			)
		)
		(property "Device Type" "C805H58"
			(at -0.0762 -8.1534 90)
			(unlocked yes)
			(layer "F.Fab")
			(hide yes)
			(effects
				(font
					(size 1.016 1.016)
					(thickness 0.1524)
				)
			)
		)
		(duplicate_pad_numbers_are_jumpers no)
		(fp_line
			(start 0.635 0)
			(end -0.635 0)
			(stroke
				(width 0.508)
				(type default)
			)
			(layer "F.SilkS")
		)
		(fp_rect
			(start -0.9652 1.778)
			(end 0.9652 -1.778)
			(stroke
				(width 0)
				(type default)
			)
			(fill no)
			(layer "F.CrtYd")
		)
		(fp_poly
			(pts
				(xy -0.9652 -1.778) (xy 0.9652 -1.778) (xy 0.9652 1.778) (xy -0.9652 1.778)
			)
			(stroke
				(width 0)
				(type default)
			)
			(fill no)
			(layer "F.Fab")
		)
		(pad "1" smd rect
			(at 0 -0.9652 90)
			(size 1.397 1.143)
			(layers "F.Cu" "F.Mask" "F.Paste")
			(net "P12V_AUX")
		)
		(pad "2" smd rect
			(at 0 0.9652 90)
			(size 1.397 1.143)
			(layers "F.Cu" "F.Mask" "F.Paste")
			(net "GND")
		)
	)
)
